# TIMECARD (Time Appliance Project (Time Card)) — schematic netlist excerpt (pin names and nets, part order shuffled) for the footprints in the layout excerpt that follows; sources: Cadence DE-HDL packaged netlist, KiCad conversion of R4006-B0001-02_R01.brd

C251  CAPACITOR  0.1UF 10V 10%  pkg SMC_0402R_H022  page 15 : \1\ = OSC_200M_CLKP ; \2\ = MHZ200CLKP_CLKIN
C74  CAPACITOR  0.1UF 25V 10%  pkg SMC_0402R_H022  page 32 : \1\ = XP12R0V ; \2\ = SG

(kicad_pcb
	(version 20260206)
	(generator "pcbnew")
	(generator_version "10.0")
	(general
		(thickness 1.6)
		(legacy_teardrops no)
	)
	(paper "A4")
	(title_block
		(title "timecard-production-celestica-r4006 — R4006-B0001-02_R01.brd")
		(comment 1 "Time Appliance Project (Time Card) / footprints 470-471 of 1113")
	)
	(layers
		(0 "F.Cu" signal "TOP")
		(4 "In1.Cu" signal "L02_GND1")
		(6 "In2.Cu" signal "L03_SIG1")
		(8 "In3.Cu" signal "L04_GND2")
		(10 "In4.Cu" signal "L05_VCC1")
		(12 "In5.Cu" signal "L06_VCC2")
		(14 "In6.Cu" signal "L07_GND3")
		(16 "In7.Cu" signal "L08_SIG2")
		(18 "In8.Cu" signal "L09_GND4")
		(2 "B.Cu" signal "BOTTOM")
		(9 "F.Adhes" user "F.Adhesive")
		(11 "B.Adhes" user "B.Adhesive")
		(13 "F.Paste" user "Package Geometry/Pastemask Top")
		(15 "B.Paste" user "Package Geometry/Pastemask Bottom")
		(5 "F.SilkS" user "Ref Des/Silkscreen Top")
		(7 "B.SilkS" user "Ref Des/Silkscreen Bottom")
		(1 "F.Mask" user "Board Geometry/Soldermask Top")
		(3 "B.Mask" user "Board Geometry/Soldermask Bottom")
		(17 "Dwgs.User" user "User.Drawings")
		(19 "Cmts.User" user "User.Comments")
		(21 "Eco1.User" user "User.Eco1")
		(23 "Eco2.User" user "User.Eco2")
		(25 "Edge.Cuts" user "Board Geometry/Outline")
		(27 "Margin" user)
		(31 "F.CrtYd" user "Package Geometry/Place Bound Top")
		(29 "B.CrtYd" user "Package Geometry/Place Bound Bottom")
		(35 "F.Fab" user "Ref Des/Assembly Top")
		(33 "B.Fab" user "Ref Des/Assembly Bottom")
	)
	(footprint ""
		(layer "F.Cu")
		(at 36.703 -94.615 -90)
		(property "Reference" "C74"
			(at 3.72237 -2.032 0)
			(unlocked yes)
			(layer "F.SilkS")
			(effects
				(font
					(size 0.7874 0.5842)
					(thickness 0.1524)
				)
			)
		)
		(property "Value" "VAL*"
			(at 0.0762 2.067306 270)
			(unlocked yes)
			(layer "F.Fab")
			(hide yes)
			(effects
				(font
					(size 0.7874 0.5842)
					(thickness 0.1524)
				)
			)
		)
		(property "Device Type" "CAPACITOR-G105-0B104-EK,0.1UF,A"
			(at 0.0508 1.127506 270)
			(unlocked yes)
			(layer "F.Fab")
			(hide yes)
			(effects
				(font
					(size 0.7874 0.5842)
					(thickness 0.1524)
				)
			)
		)
		(property "User Part Number" "PARTNUM*"
			(at 0.1016 4.023106 270)
			(unlocked yes)
			(layer "Cmts.User")
			(hide yes)
			(effects
				(font
					(size 0.7874 0.5842)
					(thickness 0.1524)
				)
			)
		)
		(property "Tolerance" "TOL*"
			(at 0.0762 3.032506 270)
			(unlocked yes)
			(layer "Cmts.User")
			(hide yes)
			(effects
				(font
					(size 0.7874 0.5842)
					(thickness 0.1524)
				)
			)
		)
		(duplicate_pad_numbers_are_jumpers no)
		(fp_line
			(start -1.143 0.5588)
			(end 1.143 0.5588)
			(stroke
				(width 0.1)
				(type default)
			)
			(layer "F.SilkS")
		)
		(fp_line
			(start 1.143 0.5588)
			(end 1.143 -0.5588)
			(stroke
				(width 0.1)
				(type default)
			)
			(layer "F.SilkS")
		)
		(fp_line
			(start -1.143 -0.5588)
			(end -1.143 0.5588)
			(stroke
				(width 0.1)
				(type default)
			)
			(layer "F.SilkS")
		)
		(fp_line
			(start 1.143 -0.5588)
			(end -1.143 -0.5588)
			(stroke
				(width 0.1)
				(type default)
			)
			(layer "F.SilkS")
		)
		(fp_rect
			(start -1.143 0.5588)
			(end 1.143 -0.5588)
			(stroke
				(width 0)
				(type default)
			)
			(fill no)
			(layer "F.CrtYd")
		)
		(fp_line
			(start -0.508 0.3048)
			(end 0.508 0.3048)
			(stroke
				(width 0.1)
				(type default)
			)
			(layer "F.Fab")
		)
		(fp_line
			(start 0.508 0.3048)
			(end 0.508 -0.3048)
			(stroke
				(width 0.1)
				(type default)
			)
			(layer "F.Fab")
		)
		(fp_line
			(start -0.508 -0.3048)
			(end -0.508 0.3048)
			(stroke
				(width 0.1)
				(type default)
			)
			(layer "F.Fab")
		)
		(fp_line
			(start 0.508 -0.3048)
			(end -0.508 -0.3048)
			(stroke
				(width 0.1)
				(type default)
			)
			(layer "F.Fab")
		)
		(pad "1" smd rect
			(at -0.5334 0 270)
			(size 0.7112 0.6096)
			(layers "F.Cu" "F.Mask" "F.Paste")
			(net "XP12R0V")
		)
		(pad "2" smd rect
			(at 0.5334 0 270)
			(size 0.7112 0.6096)
			(layers "F.Cu" "F.Mask" "F.Paste")
			(net "SG")
		)
		(zone
			(layer "F.Cu")
			(hatch none 0.5)
			(connect_pads
				(clearance 0)
			)
			(min_thickness 0.25)
			(keepout
				(tracks allowed)
				(vias not_allowed)
				(pads allowed)
				(copperpour not_allowed)
				(footprints allowed)
			)
			(placement
				(enabled no)
				(sheetname "")
			)
			(fill
				(thermal_gap 0.5)
				(thermal_bridge_width 0.5)
				(island_removal_mode 0)
			)
			(polygon
				(pts
					(xy 36.3982 -94.6912) (xy 36.3982 -94.5388) (xy 37.0078 -94.5388) (xy 37.0078 -94.6912)
				)
			)
		)
	)
	(footprint ""
		(layer "F.Cu")
		(at 112.1156 -26.7208 90)
		(property "Reference" "C251"
			(at -8.4328 -0.31623 90)
			(unlocked yes)
			(layer "F.SilkS")
			(effects
				(font
					(size 0.7874 0.5842)
					(thickness 0.1524)
				)
			)
		)
		(property "Value" "VAL*"
			(at 0.0762 2.067306 90)
			(unlocked yes)
			(layer "F.Fab")
			(hide yes)
			(effects
				(font
					(size 0.7874 0.5842)
					(thickness 0.1524)
				)
			)
		)
		(property "Device Type" "CAPACITOR-G105-0B104-CK,0.1UF,A"
			(at 0.0508 1.127506 90)
			(unlocked yes)
			(layer "F.Fab")
			(hide yes)
			(effects
				(font
					(size 0.7874 0.5842)
					(thickness 0.1524)
				)
			)
		)
		(property "User Part Number" "PARTNUM*"
			(at 0.1016 4.023106 90)
			(unlocked yes)
			(layer "Cmts.User")
			(hide yes)
			(effects
				(font
					(size 0.7874 0.5842)
					(thickness 0.1524)
				)
			)
		)
		(property "Tolerance" "TOL*"
			(at 0.0762 3.032506 90)
			(unlocked yes)
			(layer "Cmts.User")
			(hide yes)
			(effects
				(font
					(size 0.7874 0.5842)
					(thickness 0.1524)
				)
			)
		)
		(duplicate_pad_numbers_are_jumpers no)
		(fp_line
			(start 1.143 -0.5588)
			(end -1.143 -0.5588)
			(stroke
				(width 0.1)
				(type default)
			)
			(layer "F.SilkS")
		)
		(fp_line
			(start -1.143 -0.5588)
			(end -1.143 0.5588)
			(stroke
				(width 0.1)
				(type default)
			)
			(layer "F.SilkS")
		)
		(fp_line
			(start 1.143 0.5588)
			(end 1.143 -0.5588)
			(stroke
				(width 0.1)
				(type default)
			)
			(layer "F.SilkS")
		)
		(fp_line
			(start -1.143 0.5588)
			(end 1.143 0.5588)
			(stroke
				(width 0.1)
				(type default)
			)
			(layer "F.SilkS")
		)
		(fp_rect
			(start 1.143 -0.5588)
			(end -1.143 0.5588)
			(stroke
				(width 0)
				(type default)
			)
			(fill no)
			(layer "F.CrtYd")
		)
		(fp_line
			(start 0.508 -0.3048)
			(end -0.508 -0.3048)
			(stroke
				(width 0.1)
				(type default)
			)
			(layer "F.Fab")
		)
		(fp_line
			(start -0.508 -0.3048)
			(end -0.508 0.3048)
			(stroke
				(width 0.1)
				(type default)
			)
			(layer "F.Fab")
		)
		(fp_line
			(start 0.508 0.3048)
			(end 0.508 -0.3048)
			(stroke
				(width 0.1)
				(type default)
			)
			(layer "F.Fab")
		)
		(fp_line
			(start -0.508 0.3048)
			(end 0.508 0.3048)
			(stroke
				(width 0.1)
				(type default)
			)
			(layer "F.Fab")
		)
		(pad "1" smd rect
			(at -0.5334 0 90)
			(size 0.7112 0.6096)
			(layers "F.Cu" "F.Mask" "F.Paste")
			(net "OSC_200M_CLKP")
		)
		(pad "2" smd rect
			(at 0.5334 0 90)
			(size 0.7112 0.6096)
			(layers "F.Cu" "F.Mask" "F.Paste")
			(net "MHZ200CLKP_CLKIN")
		)
		(zone
			(layer "F.Cu")
			(hatch none 0.5)
			(connect_pads
				(clearance 0)
			)
			(min_thickness 0.25)
			(keepout
				(tracks allowed)
				(vias not_allowed)
				(pads allowed)
				(copperpour not_allowed)
				(footprints allowed)
			)
			(placement
				(enabled no)
				(sheetname "")
			)
			(fill
				(thermal_gap 0.5)
				(thermal_bridge_width 0.5)
				(island_removal_mode 0)
			)
			(polygon
				(pts
					(xy 111.8108 -26.797) (xy 111.8108 -26.6446) (xy 112.4204 -26.6446) (xy 112.4204 -26.797)
				)
			)
		)
	)
)
